# S9S_MB_2U (Grand Teton) — schematic netlist excerpt (pin names and nets, part order shuffled) for the footprints in the layout excerpt that follows; sources: Cadence DE-HDL packaged netlist, KiCad conversion of 03242023_DA0F0TMBIJ0_F0T_Motherboard_J_brd_V01_OCP.brd

PC449_P1_2  Q_CAP  22UF 16V 20% X6S  pkg C0805  page 293 : A = SW_P12V_PVCCINFAON_CPU1_FLT ; B = GND
R249  Q_RES  240 1% EMPTY  pkg 0402LF  page 120 : A = PVNN_TERM_CPU0 ; B = FM_S3M_CPU0_LVC1_GPIO_0
C1390  Q_CAP  47UF 4V 20% X6S  pkg C0805  page 78 : A = PVPP_HBM_CPU1 ; B = GND

(kicad_pcb
	(version 20260206)
	(generator "pcbnew")
	(generator_version "10.0")
	(general
		(thickness 1.6)
		(legacy_teardrops no)
	)
	(paper "A4")
	(title_block
		(title "03242023_DA0F0TMBIJ0_F0T_Motherboard_J_brd_V01_OCP.brd")
		(comment 1 "Grand Teton / footprints 5251-5253 of 6105")
	)
	(layers
		(0 "F.Cu" signal "TOP")
		(4 "In1.Cu" signal "GND")
		(6 "In2.Cu" signal "IN1")
		(8 "In3.Cu" signal "GND1")
		(10 "In4.Cu" signal "IN2")
		(12 "In5.Cu" signal "GND2")
		(14 "In6.Cu" signal "IN3")
		(16 "In7.Cu" signal "GND3")
		(18 "In8.Cu" signal "VCC")
		(20 "In9.Cu" signal "VCC1")
		(22 "In10.Cu" signal "GND4")
		(24 "In11.Cu" signal "IN4")
		(26 "In12.Cu" signal "GND5")
		(28 "In13.Cu" signal "IN5")
		(30 "In14.Cu" signal "GND6")
		(32 "In15.Cu" signal "IN6")
		(34 "In16.Cu" signal "GND7")
		(2 "B.Cu" signal "BOTTOM")
		(9 "F.Adhes" user "F.Adhesive")
		(11 "B.Adhes" user "B.Adhesive")
		(13 "F.Paste" user "Package Geometry/Pastemask Top")
		(15 "B.Paste" user "Package Geometry/Pastemask Bottom")
		(5 "F.SilkS" user "Ref Des/Silkscreen Top")
		(7 "B.SilkS" user "Ref Des/Silkscreen Bottom")
		(1 "F.Mask" user "Board Geometry/Soldermask Top")
		(3 "B.Mask" user "Board Geometry/Soldermask Bottom")
		(17 "Dwgs.User" user "User.Drawings")
		(19 "Cmts.User" user "User.Comments")
		(21 "Eco1.User" user "User.Eco1")
		(23 "Eco2.User" user "User.Eco2")
		(25 "Edge.Cuts" user "Board Geometry/Outline")
		(27 "Margin" user)
		(31 "F.CrtYd" user "Package Geometry/Place Bound Top")
		(29 "B.CrtYd" user "Package Geometry/Place Bound Bottom")
		(35 "F.Fab" user "Ref Des/Assembly Top")
		(33 "B.Fab" user "Ref Des/Assembly Bottom")
	)
	(footprint ""
		(layer "B.Cu")
		(at 143.793718 -335.62798)
		(property "Reference" "C1390"
			(at 0 0 0)
			(layer "B.SilkS")
			(hide yes)
			(effects
				(font
					(size 1.27 1.27)
				)
				(justify mirror)
			)
		)
		(property "Value" ""
			(at 0 0 0)
			(layer "B.Fab")
			(effects
				(font
					(size 1.27 1.27)
				)
				(justify mirror)
			)
		)
		(duplicate_pad_numbers_are_jumpers no)
		(fp_line
			(start -1.524 -0.762)
			(end -1.524 0.762)
			(stroke
				(width 0.1524)
				(type default)
			)
			(layer "B.SilkS")
		)
		(fp_line
			(start -1.524 0.762)
			(end 1.524 0.762)
			(stroke
				(width 0.1524)
				(type default)
			)
			(layer "B.SilkS")
		)
		(fp_line
			(start 1.524 -0.762)
			(end -1.524 -0.762)
			(stroke
				(width 0.1524)
				(type default)
			)
			(layer "B.SilkS")
		)
		(fp_line
			(start 1.524 0.762)
			(end 1.524 -0.762)
			(stroke
				(width 0.1524)
				(type default)
			)
			(layer "B.SilkS")
		)
		(fp_line
			(start -1.1049 -0.724916)
			(end 1.1049 -0.724916)
			(stroke
				(width 0.1)
				(type default)
			)
			(layer "B.Fab")
		)
		(fp_line
			(start -1.1049 0.724916)
			(end -1.1049 -0.724916)
			(stroke
				(width 0.1)
				(type default)
			)
			(layer "B.Fab")
		)
		(fp_line
			(start 1.1049 -0.724916)
			(end 1.1049 0.724916)
			(stroke
				(width 0.1)
				(type default)
			)
			(layer "B.Fab")
		)
		(fp_line
			(start 1.1049 0.724916)
			(end -1.1049 0.724916)
			(stroke
				(width 0.1)
				(type default)
			)
			(layer "B.Fab")
		)
		(pad "1" smd rect
			(at 0.889 0)
			(size 1.016 1.27)
			(layers "B.Cu" "B.Mask" "B.Paste")
			(net "PVPP_HBM_CPU1")
		)
		(pad "2" smd rect
			(at -0.889 0)
			(size 1.016 1.27)
			(layers "B.Cu" "B.Mask" "B.Paste")
			(net "GND")
		)
	)
	(footprint ""
		(layer "B.Cu")
		(at 277.138384 -193.669666 -90)
		(property "Reference" "R249"
			(at 0 0 90)
			(layer "B.SilkS")
			(hide yes)
			(effects
				(font
					(size 1.27 1.27)
				)
				(justify mirror)
			)
		)
		(property "Value" ""
			(at 0 0 90)
			(layer "B.Fab")
			(effects
				(font
					(size 1.27 1.27)
				)
				(justify mirror)
			)
		)
		(duplicate_pad_numbers_are_jumpers no)
		(fp_line
			(start -0.7874 0.4064)
			(end 0.7874 0.4064)
			(stroke
				(width 0.1524)
				(type default)
			)
			(layer "B.SilkS")
		)
		(fp_line
			(start 0.7874 0.4064)
			(end 0.7874 -0.4064)
			(stroke
				(width 0.1524)
				(type default)
			)
			(layer "B.SilkS")
		)
		(fp_line
			(start -0.7874 -0.4064)
			(end -0.7874 0.4064)
			(stroke
				(width 0.1524)
				(type default)
			)
			(layer "B.SilkS")
		)
		(fp_line
			(start 0.7874 -0.4064)
			(end -0.7874 -0.4064)
			(stroke
				(width 0.1524)
				(type default)
			)
			(layer "B.SilkS")
		)
		(fp_line
			(start -0.67945 0.3048)
			(end -0.120396 0.3048)
			(stroke
				(width 0.1)
				(type default)
			)
			(layer "B.Fab")
		)
		(fp_line
			(start -0.120396 0.3048)
			(end -0.120396 0.2794)
			(stroke
				(width 0.1)
				(type default)
			)
			(layer "B.Fab")
		)
		(fp_line
			(start 0.12065 0.3048)
			(end 0.67945 0.3048)
			(stroke
				(width 0.1)
				(type default)
			)
			(layer "B.Fab")
		)
		(fp_line
			(start 0.67945 0.3048)
			(end 0.67945 -0.305054)
			(stroke
				(width 0.1)
				(type default)
			)
			(layer "B.Fab")
		)
		(fp_line
			(start -0.120396 0.2794)
			(end 0.12065 0.2794)
			(stroke
				(width 0.1)
				(type default)
			)
			(layer "B.Fab")
		)
		(fp_line
			(start 0.12065 0.2794)
			(end 0.12065 0.3048)
			(stroke
				(width 0.1)
				(type default)
			)
			(layer "B.Fab")
		)
		(fp_line
			(start -0.12065 -0.2794)
			(end -0.12065 -0.3048)
			(stroke
				(width 0.1)
				(type default)
			)
			(layer "B.Fab")
		)
		(fp_line
			(start 0.12065 -0.2794)
			(end -0.12065 -0.2794)
			(stroke
				(width 0.1)
				(type default)
			)
			(layer "B.Fab")
		)
		(fp_line
			(start -0.67945 -0.3048)
			(end -0.67945 0.3048)
			(stroke
				(width 0.1)
				(type default)
			)
			(layer "B.Fab")
		)
		(fp_line
			(start -0.12065 -0.3048)
			(end -0.67945 -0.3048)
			(stroke
				(width 0.1)
				(type default)
			)
			(layer "B.Fab")
		)
		(fp_line
			(start 0.12065 -0.305054)
			(end 0.12065 -0.2794)
			(stroke
				(width 0.1)
				(type default)
			)
			(layer "B.Fab")
		)
		(fp_line
			(start 0.67945 -0.305054)
			(end 0.12065 -0.305054)
			(stroke
				(width 0.1)
				(type default)
			)
			(layer "B.Fab")
		)
		(pad "1" smd circle
			(at 0.40005 0 90)
			(size 0 0)
			(layers "B.Cu" "B.Mask" "B.Paste")
			(net "PVNN_TERM_CPU0")
		)
		(pad "2" smd circle
			(at -0.40005 0 90)
			(size 0 0)
			(layers "B.Cu" "B.Mask" "B.Paste")
			(net "FM_S3M_CPU0_LVC1_GPIO_0")
		)
	)
	(footprint ""
		(layer "B.Cu")
		(at 54.880002 -151.098758 180)
		(property "Reference" "PC449_P1_2"
			(at 0 0 0)
			(layer "B.SilkS")
			(hide yes)
			(effects
				(font
					(size 1.27 1.27)
				)
				(justify mirror)
			)
		)
		(property "Value" ""
			(at 0 0 0)
			(layer "B.Fab")
			(effects
				(font
					(size 1.27 1.27)
				)
				(justify mirror)
			)
		)
		(duplicate_pad_numbers_are_jumpers no)
		(fp_line
			(start 1.524 0.762)
			(end 1.524 -0.762)
			(stroke
				(width 0.1524)
				(type default)
			)
			(layer "B.SilkS")
		)
		(fp_line
			(start 1.524 -0.762)
			(end -1.524 -0.762)
			(stroke
				(width 0.1524)
				(type default)
			)
			(layer "B.SilkS")
		)
		(fp_line
			(start -1.524 0.762)
			(end 1.524 0.762)
			(stroke
				(width 0.1524)
				(type default)
			)
			(layer "B.SilkS")
		)
		(fp_line
			(start -1.524 -0.762)
			(end -1.524 0.762)
			(stroke
				(width 0.1524)
				(type default)
			)
			(layer "B.SilkS")
		)
		(fp_line
			(start 1.1049 0.724916)
			(end -1.1049 0.724916)
			(stroke
				(width 0.1)
				(type default)
			)
			(layer "B.Fab")
		)
		(fp_line
			(start 1.1049 -0.724916)
			(end 1.1049 0.724916)
			(stroke
				(width 0.1)
				(type default)
			)
			(layer "B.Fab")
		)
		(fp_line
			(start -1.1049 0.724916)
			(end -1.1049 -0.724916)
			(stroke
				(width 0.1)
				(type default)
			)
			(layer "B.Fab")
		)
		(fp_line
			(start -1.1049 -0.724916)
			(end 1.1049 -0.724916)
			(stroke
				(width 0.1)
				(type default)
			)
			(layer "B.Fab")
		)
		(pad "1" smd rect
			(at 0.889 0 180)
			(size 1.016 1.27)
			(layers "B.Cu" "B.Mask" "B.Paste")
			(net "SW_P12V_PVCCINFAON_CPU1_FLT")
		)
		(pad "2" smd rect
			(at -0.889 0 180)
			(size 1.016 1.27)
			(layers "B.Cu" "B.Mask" "B.Paste")
			(net "GND")
		)
	)
)
